(kicad_pcb
	(version 20221018)
	(generator pcbnew)
	(general
    (thickness 1.518)
  )
	(paper "A4")
	(title_block
    (title "Kria K26 Devboard")
    (date "2024-03-26")
    (rev "1.2.5")
    (comment 1 "www.antmicro.com")
    (comment 2 "Antmicro Ltd.")
		(comment 9 "footprints 589-596 of 660")
	)
	(layers
    (0 "F.Cu" mixed)
    (1 "In1.Cu" power)
    (2 "In2.Cu" mixed)
    (3 "In3.Cu" power)
    (4 "In4.Cu" mixed)
    (5 "In5.Cu" power)
    (6 "In6.Cu" mixed)
    (31 "B.Cu" power)
    (32 "B.Adhes" user "B.Adhesive")
    (33 "F.Adhes" user "F.Adhesive")
    (34 "B.Paste" user)
    (35 "F.Paste" user)
    (36 "B.SilkS" user "B.Silkscreen")
    (37 "F.SilkS" user "F.Silkscreen")
    (38 "B.Mask" user)
    (39 "F.Mask" user)
    (40 "Dwgs.User" user "User.Drawings")
    (41 "Cmts.User" user "User.Comments")
    (42 "Eco1.User" user "User.Eco1")
    (43 "Eco2.User" user "User.Eco2")
    (44 "Edge.Cuts" user)
    (45 "Margin" user)
    (46 "B.CrtYd" user "B.Courtyard")
    (47 "F.CrtYd" user "F.Courtyard")
    (48 "B.Fab" user)
    (49 "F.Fab" user)
  )
	(footprint "kria-k26-devboard-footprints:TSOT23-6" (layer "B.Cu")
    (at 140.524999 80.975001 90)
    (property "Author" "Antmicro")
    (property "License" "Apache-2.0")
    (property "MPN" "AP62301WU-7")
    (property "Manufacturer" "Diodes Incorporated")
    (property "Sheetfile" "dc-dc-conventers.kicad_sch")
    (property "Sheetname" "DC/DC conventers")
    (property "ki_description" "DC-DC Switching Synchronous Buck Regulator, Adjustable, 4.2V-18Vin, 0.8V-7V/3A out, TSOT-26-6")
    (property "ki_keywords" "SMT, PMIC, IC, VOLTAGE")
    (attr smd)
    (fp_text reference "U50" (at 1.675001 0.575001) (layer "B.SilkS")
        (effects (font (size 0.7 0.7) (thickness 0.15)) (justify left bottom mirror))
    )
    (fp_text value "AP62301_TSOT" (at -0.005 -2.6 270) (layer "B.Fab") hide
        (effects (font (size 0.7 0.7) (thickness 0.15)) (justify left bottom mirror))
    )
    (fp_text user "License: Apache-2.0" (at -1.893 -4.967 270) (layer "B.Fab") hide
        (effects (font (size 0.7 0.7) (thickness 0.15)) (justify left bottom mirror))
    )
    (fp_text user "${REFERENCE}" (at -1.893 -6.168 270) (layer "B.Fab") hide
        (effects (font (size 0.7 0.7) (thickness 0.15)) (justify left bottom mirror))
    )
    (fp_text user "Author: Antmicro" (at -1.893 -7.368 270) (layer "B.Fab") hide
        (effects (font (size 0.7 0.7) (thickness 0.15)) (justify left bottom mirror))
    )
    (fp_line (start -1.4805 -0.725) (end -1.4795 0.725)
      (stroke (width 0.15) (type solid)) (layer "B.SilkS"))
    (fp_line (start -1.4805 -0.725) (end -1.3905 -0.725)
      (stroke (width 0.15) (type solid)) (layer "B.SilkS"))
    (fp_line (start -1.4795 0.725) (end -1.3905 0.725)
      (stroke (width 0.15) (type solid)) (layer "B.SilkS"))
    (fp_line (start 1.479 -0.73) (end 1.38 -0.73)
      (stroke (width 0.15) (type solid)) (layer "B.SilkS"))
    (fp_line (start 1.48 0.72) (end 1.38 0.72)
      (stroke (width 0.15) (type solid)) (layer "B.SilkS"))
    (fp_line (start 1.48 0.72) (end 1.479 -0.73)
      (stroke (width 0.15) (type solid)) (layer "B.SilkS"))
    (fp_circle (center -1.499 -1.236) (end -1.45 -1.236)
      (stroke (width 0.15) (type solid)) (fill solid) (layer "B.SilkS"))
    (fp_rect (start -1.65 1.61) (end 1.65 -1.61)
      (stroke (width 0.05) (type solid)) (fill none) (layer "B.CrtYd"))
    (fp_line (start -1.527 -0.491) (end -1.527 0.833)
      (stroke (width 0.15) (type solid)) (layer "B.Fab"))
    (fp_line (start -1.527 -0.491) (end -1.102 -0.916)
      (stroke (width 0.15) (type solid)) (layer "B.Fab"))
    (fp_line (start -1.527 0.833) (end 1.523 0.833)
      (stroke (width 0.15) (type solid)) (layer "B.Fab"))
    (fp_line (start -1.102 -0.916) (end 1.523 -0.916)
      (stroke (width 0.15) (type solid)) (layer "B.Fab"))
    (fp_line (start 1.523 0.833) (end 1.523 -0.916)
      (stroke (width 0.15) (type solid)) (layer "B.Fab"))
    (pad "1" smd rect (at -0.952 -1.18 90) (size 0.7 0.8) (layers "B.Cu" "B.Paste" "B.Mask")
      (net 1 "GND") (pinfunction "GND") (pintype "power_in"))
    (pad "2" smd rect (at -0.001 -1.18 90) (size 0.7 0.8) (layers "B.Cu" "B.Paste" "B.Mask")
      (net 310 "/Power Supply/DC/DC conventers/SW_PS_2V5") (pinfunction "SW") (pintype "power_out"))
    (pad "3" smd rect (at 0.947 -1.18 90) (size 0.7 0.8) (layers "B.Cu" "B.Paste" "B.Mask")
      (net 14 "/Power Supply/DC/DC conventers/DC_MAIN_BUS") (pinfunction "VIN") (pintype "power_in"))
    (pad "4" smd rect (at 0.947 1.18 90) (size 0.7 0.8) (layers "B.Cu" "B.Paste" "B.Mask")
      (net 689 "Net-(U50-FB)") (pinfunction "FB") (pintype "input"))
    (pad "5" smd rect (at -0.001 1.18 90) (size 0.7 0.8) (layers "B.Cu" "B.Paste" "B.Mask")
      (net 687 "Net-(U50-EN)") (pinfunction "EN") (pintype "input"))
    (pad "6" smd rect (at -0.952 1.18 90) (size 0.7 0.8) (layers "B.Cu" "B.Paste" "B.Mask")
      (net 258 "Net-(U50-BST)") (pinfunction "BST") (pintype "output"))
  )
	(footprint "kria-k26-devboard-footprints:R_0402_1005Metric" (layer "B.Cu")
    (at 103.5 137.915 -90)
    (descr "Resistor SMD 0402")
    (tags "resistor SMD 0402")
    (property "Author" "Antmicro")
    (property "Current" "1A")
    (property "DNP" "DNP")
    (property "License" "Apache-2.0")
    (property "MPN" "ERJ2GE0R00X")
    (property "Manufacturer" "Panasonic")
    (property "Sheetfile" "i2c.kicad_sch")
    (property "Sheetname" "I2C ")
    (property "Tolerance" "")
    (property "Val" "0R")
    (property "dnp" "")
    (property "exclude_from_bom" "")
    (property "ki_description" "0R resistor in 0402 package with unspecified tolerance")
    (attr exclude_from_pos_files exclude_from_bom)
    (fp_text reference "R37" (at -1.055 0.59 90) (layer "B.SilkS")
        (effects (font (size 0.7 0.7) (thickness 0.15)) (justify left bottom mirror))
    )
    (fp_text value "R_0R_0402" (at 0 -1.4 90) (layer "B.Fab") hide
        (effects (font (size 0.7 0.7) (thickness 0.15)) (justify left bottom mirror))
    )
    (fp_text user "Author: Antmicro" (at -0.95 -4.169 90) (layer "B.Fab") hide
        (effects (font (size 0.7 0.7) (thickness 0.15)) (justify left bottom mirror))
    )
    (fp_text user "${REFERENCE}" (at -0.95 -3.168 90) (layer "B.Fab") hide
        (effects (font (size 0.7 0.7) (thickness 0.15)) (justify left bottom mirror))
    )
    (fp_text user "License: Apache-2.0" (at -0.95 -5.169 90) (layer "B.Fab") hide
        (effects (font (size 0.7 0.7) (thickness 0.15)) (justify left bottom mirror))
    )
    (fp_rect (start -0.93 0.47) (end 0.93 -0.47)
      (stroke (width 0.05) (type solid)) (fill none) (layer "B.CrtYd"))
    (fp_rect (start -0.5 0.25) (end 0.5 -0.25)
      (stroke (width 0.15) (type solid)) (fill none) (layer "B.Fab"))
    (pad "1" smd roundrect (at -0.485 0 270) (size 0.59 0.64) (layers "B.Cu" "B.Paste" "B.Mask") (roundrect_rratio 0.25)
      (net 186 "/Debug and JTAG/~{EEPROM_WC}") (pintype "passive"))
    (pad "2" smd roundrect (at 0.485 0 270) (size 0.59 0.64) (layers "B.Cu" "B.Paste" "B.Mask") (roundrect_rratio 0.25)
      (net 1 "GND") (pintype "passive"))
  )
	(footprint "kria-k26-devboard-footprints:C_2220_5650Metric" (layer "B.Cu")
    (at 165.22 82.95 90)
    (descr "Capacitor SMD 2220")
    (tags "capacitor SMD 2220")
    (property "Author" "Antmicro")
    (property "DNP" "DNP")
    (property "Dielectric" "")
    (property "License" "Apache-2.0")
    (property "MPN" "C5750X7S2A226M280KB")
    (property "Manufacturer" "TDK")
    (property "Sheetfile" "PoE.kicad_sch")
    (property "Sheetname" "PoE")
    (property "Val" "22u/100V")
    (property "Voltage" "")
    (property "dnp" "")
    (property "exclude_from_bom" "")
    (property "ki_description" " ")
    (attr exclude_from_pos_files exclude_from_bom)
    (fp_text reference "C176" (at 6.61 0.785 270) (layer "B.SilkS")
        (effects (font (size 0.7 0.7) (thickness 0.15)) (justify left bottom mirror))
    )
    (fp_text value "C_22u_100V_2220" (at 0 -3.9 270) (layer "B.Fab") hide
        (effects (font (size 0.7 0.7) (thickness 0.15)) (justify left bottom mirror))
    )
    (fp_text user "License: Apache-2.0" (at -3.7 -6.9 270) (layer "B.Fab") hide
        (effects (font (size 0.7 0.7) (thickness 0.15)) (justify left bottom mirror))
    )
    (fp_text user "Author: Antmicro" (at -3.7 -7.9 270) (layer "B.Fab") hide
        (effects (font (size 0.7 0.7) (thickness 0.15)) (justify left bottom mirror))
    )
    (fp_text user "${REFERENCE}" (at -3.7 -5.9 270) (layer "B.Fab") hide
        (effects (font (size 0.7 0.7) (thickness 0.15)) (justify left bottom mirror))
    )
    (fp_line (start -1.415 -2.61) (end 1.415 -2.61)
      (stroke (width 0.15) (type solid)) (layer "B.SilkS"))
    (fp_line (start -1.415 2.61) (end 1.415 2.61)
      (stroke (width 0.15) (type solid)) (layer "B.SilkS"))
    (fp_rect (start -3.7 2.95) (end 3.7 -2.95)
      (stroke (width 0.05) (type solid)) (fill none) (layer "B.CrtYd"))
    (fp_rect (start -2.85 2.5) (end 2.85 -2.5)
      (stroke (width 0.15) (type solid)) (fill none) (layer "B.Fab"))
    (pad "1" smd roundrect (at -2.55 0 90) (size 1.8 5.4) (layers "B.Cu" "B.Paste" "B.Mask") (roundrect_rratio 0.138889)
      (net 9 "/Power Supply/PoE/VDD_POE_IN") (pintype "passive"))
    (pad "2" smd roundrect (at 2.55 0 90) (size 1.8 5.4) (layers "B.Cu" "B.Paste" "B.Mask") (roundrect_rratio 0.138889)
      (net 11 "GNDD") (pintype "passive"))
  )
	(footprint "kria-k26-devboard-footprints:C_2220_5650Metric" (layer "B.Cu")
    (at 182.99 82.95 90)
    (descr "Capacitor SMD 2220")
    (tags "capacitor SMD 2220")
    (property "Author" "Antmicro")
    (property "DNP" "DNP")
    (property "Dielectric" "")
    (property "License" "Apache-2.0")
    (property "MPN" "C5750X7S2A226M280KB")
    (property "Manufacturer" "TDK")
    (property "Sheetfile" "PoE.kicad_sch")
    (property "Sheetname" "PoE")
    (property "Val" "22u/100V")
    (property "Voltage" "")
    (property "dnp" "")
    (property "exclude_from_bom" "")
    (property "ki_description" " ")
    (attr exclude_from_pos_files exclude_from_bom)
    (fp_text reference "C178" (at 6.61 0.785 270) (layer "B.SilkS")
        (effects (font (size 0.7 0.7) (thickness 0.15)) (justify left bottom mirror))
    )
    (fp_text value "C_22u_100V_2220" (at 0 -3.9 270) (layer "B.Fab") hide
        (effects (font (size 0.7 0.7) (thickness 0.15)) (justify left bottom mirror))
    )
    (fp_text user "Author: Antmicro" (at -3.7 -7.9 270) (layer "B.Fab") hide
        (effects (font (size 0.7 0.7) (thickness 0.15)) (justify left bottom mirror))
    )
    (fp_text user "${REFERENCE}" (at -3.7 -5.9 270) (layer "B.Fab") hide
        (effects (font (size 0.7 0.7) (thickness 0.15)) (justify left bottom mirror))
    )
    (fp_text user "License: Apache-2.0" (at -3.7 -6.9 270) (layer "B.Fab") hide
        (effects (font (size 0.7 0.7) (thickness 0.15)) (justify left bottom mirror))
    )
    (fp_line (start -1.415 -2.61) (end 1.415 -2.61)
      (stroke (width 0.15) (type solid)) (layer "B.SilkS"))
    (fp_line (start -1.415 2.61) (end 1.415 2.61)
      (stroke (width 0.15) (type solid)) (layer "B.SilkS"))
    (fp_rect (start -3.7 2.95) (end 3.7 -2.95)
      (stroke (width 0.05) (type solid)) (fill none) (layer "B.CrtYd"))
    (fp_rect (start -2.85 2.5) (end 2.85 -2.5)
      (stroke (width 0.15) (type solid)) (fill none) (layer "B.Fab"))
    (pad "1" smd roundrect (at -2.55 0 90) (size 1.8 5.4) (layers "B.Cu" "B.Paste" "B.Mask") (roundrect_rratio 0.138889)
      (net 9 "/Power Supply/PoE/VDD_POE_IN") (pintype "passive"))
    (pad "2" smd roundrect (at 2.55 0 90) (size 1.8 5.4) (layers "B.Cu" "B.Paste" "B.Mask") (roundrect_rratio 0.138889)
      (net 11 "GNDD") (pintype "passive"))
  )
	(footprint "kria-k26-devboard-footprints:C_2220_5650Metric" (layer "B.Cu")
    (at 177.075 82.95 90)
    (descr "Capacitor SMD 2220")
    (tags "capacitor SMD 2220")
    (property "Author" "Antmicro")
    (property "DNP" "DNP")
    (property "Dielectric" "")
    (property "License" "Apache-2.0")
    (property "MPN" "C5750X7S2A226M280KB")
    (property "Manufacturer" "TDK")
    (property "Sheetfile" "PoE.kicad_sch")
    (property "Sheetname" "PoE")
    (property "Val" "22u/100V")
    (property "Voltage" "")
    (property "dnp" "")
    (property "exclude_from_bom" "")
    (property "ki_description" " ")
    (attr exclude_from_pos_files exclude_from_bom)
    (fp_text reference "C179" (at 6.61 0.785 270) (layer "B.SilkS")
        (effects (font (size 0.7 0.7) (thickness 0.15)) (justify left bottom mirror))
    )
    (fp_text value "C_22u_100V_2220" (at 0 -3.9 270) (layer "B.Fab") hide
        (effects (font (size 0.7 0.7) (thickness 0.15)) (justify left bottom mirror))
    )
    (fp_text user "License: Apache-2.0" (at -3.7 -6.9 270) (layer "B.Fab") hide
        (effects (font (size 0.7 0.7) (thickness 0.15)) (justify left bottom mirror))
    )
    (fp_text user "Author: Antmicro" (at -3.7 -7.9 270) (layer "B.Fab") hide
        (effects (font (size 0.7 0.7) (thickness 0.15)) (justify left bottom mirror))
    )
    (fp_text user "${REFERENCE}" (at -3.7 -5.9 270) (layer "B.Fab") hide
        (effects (font (size 0.7 0.7) (thickness 0.15)) (justify left bottom mirror))
    )
    (fp_line (start -1.415 -2.61) (end 1.415 -2.61)
      (stroke (width 0.15) (type solid)) (layer "B.SilkS"))
    (fp_line (start -1.415 2.61) (end 1.415 2.61)
      (stroke (width 0.15) (type solid)) (layer "B.SilkS"))
    (fp_rect (start -3.7 2.95) (end 3.7 -2.95)
      (stroke (width 0.05) (type solid)) (fill none) (layer "B.CrtYd"))
    (fp_rect (start -2.85 2.5) (end 2.85 -2.5)
      (stroke (width 0.15) (type solid)) (fill none) (layer "B.Fab"))
    (pad "1" smd roundrect (at -2.55 0 90) (size 1.8 5.4) (layers "B.Cu" "B.Paste" "B.Mask") (roundrect_rratio 0.138889)
      (net 9 "/Power Supply/PoE/VDD_POE_IN") (pintype "passive"))
    (pad "2" smd roundrect (at 2.55 0 90) (size 1.8 5.4) (layers "B.Cu" "B.Paste" "B.Mask") (roundrect_rratio 0.138889)
      (net 11 "GNDD") (pintype "passive"))
  )
	(footprint "kria-k26-devboard-footprints:C_2220_5650Metric" (layer "B.Cu")
    (at 171.15 82.95 90)
    (descr "Capacitor SMD 2220")
    (tags "capacitor SMD 2220")
    (property "Author" "Antmicro")
    (property "DNP" "DNP")
    (property "Dielectric" "")
    (property "License" "Apache-2.0")
    (property "MPN" "C5750X7S2A226M280KB")
    (property "Manufacturer" "TDK")
    (property "Sheetfile" "PoE.kicad_sch")
    (property "Sheetname" "PoE")
    (property "Val" "22u/100V")
    (property "Voltage" "")
    (property "dnp" "")
    (property "exclude_from_bom" "")
    (property "ki_description" " ")
    (attr exclude_from_pos_files exclude_from_bom)
    (fp_text reference "C177" (at 6.61 0.785 270) (layer "B.SilkS")
        (effects (font (size 0.7 0.7) (thickness 0.15)) (justify left bottom mirror))
    )
    (fp_text value "C_22u_100V_2220" (at 0 -3.9 270) (layer "B.Fab") hide
        (effects (font (size 0.7 0.7) (thickness 0.15)) (justify left bottom mirror))
    )
    (fp_text user "License: Apache-2.0" (at -3.7 -6.9 270) (layer "B.Fab") hide
        (effects (font (size 0.7 0.7) (thickness 0.15)) (justify left bottom mirror))
    )
    (fp_text user "${REFERENCE}" (at -3.7 -5.9 270) (layer "B.Fab") hide
        (effects (font (size 0.7 0.7) (thickness 0.15)) (justify left bottom mirror))
    )
    (fp_text user "Author: Antmicro" (at -3.7 -7.9 270) (layer "B.Fab") hide
        (effects (font (size 0.7 0.7) (thickness 0.15)) (justify left bottom mirror))
    )
    (fp_line (start -1.415 -2.61) (end 1.415 -2.61)
      (stroke (width 0.15) (type solid)) (layer "B.SilkS"))
    (fp_line (start -1.415 2.61) (end 1.415 2.61)
      (stroke (width 0.15) (type solid)) (layer "B.SilkS"))
    (fp_rect (start -3.7 2.95) (end 3.7 -2.95)
      (stroke (width 0.05) (type solid)) (fill none) (layer "B.CrtYd"))
    (fp_rect (start -2.85 2.5) (end 2.85 -2.5)
      (stroke (width 0.15) (type solid)) (fill none) (layer "B.Fab"))
    (pad "1" smd roundrect (at -2.55 0 90) (size 1.8 5.4) (layers "B.Cu" "B.Paste" "B.Mask") (roundrect_rratio 0.138889)
      (net 9 "/Power Supply/PoE/VDD_POE_IN") (pintype "passive"))
    (pad "2" smd roundrect (at 2.55 0 90) (size 1.8 5.4) (layers "B.Cu" "B.Paste" "B.Mask") (roundrect_rratio 0.138889)
      (net 11 "GNDD") (pintype "passive"))
  )
	(footprint "kria-k26-devboard-footprints:R_0402_1005Metric" (layer "B.Cu")
    (at 139.55 87.35 90)
    (descr "Resistor SMD 0402")
    (tags "resistor SMD 0402")
    (property "Author" "Antmicro")
    (property "Current" "1A")
    (property "License" "Apache-2.0")
    (property "MPN" "ERJ2GE0R00X")
    (property "Manufacturer" "Panasonic")
    (property "Sheetfile" "dc-dc-conventers.kicad_sch")
    (property "Sheetname" "DC/DC conventers")
    (property "Tolerance" "")
    (property "Val" "0R")
    (property "ki_description" "0R resistor in 0402 package with unspecified tolerance")
    (attr smd)
    (fp_text reference "R127" (at 1.68 1.33 270) (layer "B.SilkS")
        (effects (font (size 0.7 0.7) (thickness 0.15)) (justify left bottom mirror))
    )
    (fp_text value "R_0R_0402" (at 0 -1.4 270) (layer "B.Fab") hide
        (effects (font (size 0.7 0.7) (thickness 0.15)) (justify left bottom mirror))
    )
    (fp_text user "Author: Antmicro" (at -0.95 -4.169 270) (layer "B.Fab") hide
        (effects (font (size 0.7 0.7) (thickness 0.15)) (justify left bottom mirror))
    )
    (fp_text user "${REFERENCE}" (at -0.95 -3.168 270) (layer "B.Fab") hide
        (effects (font (size 0.7 0.7) (thickness 0.15)) (justify left bottom mirror))
    )
    (fp_text user "License: Apache-2.0" (at -0.95 -5.169 270) (layer "B.Fab") hide
        (effects (font (size 0.7 0.7) (thickness 0.15)) (justify left bottom mirror))
    )
    (fp_rect (start -0.93 0.47) (end 0.93 -0.47)
      (stroke (width 0.05) (type solid)) (fill none) (layer "B.CrtYd"))
    (fp_rect (start -0.5 0.25) (end 0.5 -0.25)
      (stroke (width 0.15) (type solid)) (fill none) (layer "B.Fab"))
    (pad "1" smd roundrect (at -0.485 0 90) (size 0.59 0.64) (layers "B.Cu" "B.Paste" "B.Mask") (roundrect_rratio 0.25)
      (net 185 "/Clock distribution/PS_CLK_EN") (pintype "passive"))
    (pad "2" smd roundrect (at 0.485 0 90) (size 0.59 0.64) (layers "B.Cu" "B.Paste" "B.Mask") (roundrect_rratio 0.25)
      (net 687 "Net-(U50-EN)") (pintype "passive"))
  )
	(footprint "kria-k26-devboard-footprints:R_2010_5025Metric" (layer "B.Cu")
    (at 177.55 94.45)
    (descr "Resistor SMD 2010")
    (tags "resistor SMD 2010")
    (property "Author" "Antmicro")
    (property "License" "Apache-2.0")
    (property "MPN" "CR2010-FX-1502ELF")
    (property "Manufacturer" "Bourns")
    (property "Sheetfile" "PoE.kicad_sch")
    (property "Sheetname" "PoE")
    (property "Tolerance" "1%")
    (property "Val" "15k")
    (property "ki_description" "15k resistor in 2010 package with 1% tolerance")
    (attr smd)
    (fp_text reference "R154" (at 1.44 2.36 180) (layer "B.SilkS")
        (effects (font (size 0.7 0.7) (thickness 0.15)) (justify left bottom mirror))
    )
    (fp_text value "R_15k_2010" (at 0 -2.7 180) (layer "B.Fab") hide
        (effects (font (size 0.7 0.7) (thickness 0.15)) (justify left bottom mirror))
    )
    (fp_text user "${REFERENCE}" (at -3.34 -4.278 180) (layer "B.Fab") hide
        (effects (font (size 0.7 0.7) (thickness 0.15)) (justify left bottom mirror))
    )
    (fp_text user "Author: Antmicro" (at -3.34 -5.278 180) (layer "B.Fab") hide
        (effects (font (size 0.7 0.7) (thickness 0.15)) (justify left bottom mirror))
    )
    (fp_text user "License: Apache-2.0" (at -3.34 -6.278 180) (layer "B.Fab") hide
        (effects (font (size 0.7 0.7) (thickness 0.15)) (justify left bottom mirror))
    )
    (fp_line (start -1.4 -1.36) (end 1.4 -1.36)
      (stroke (width 0.15) (type solid)) (layer "B.SilkS"))
    (fp_line (start -1.4 1.36) (end 1.4 1.36)
      (stroke (width 0.15) (type solid)) (layer "B.SilkS"))
    (fp_rect (start -3.34 1.75) (end 3.34 -1.75)
      (stroke (width 0.05) (type solid)) (fill none) (layer "B.CrtYd"))
    (fp_rect (start -2.5 1.25) (end 2.5 -1.25)
      (stroke (width 0.15) (type solid)) (fill none) (layer "B.Fab"))
    (pad "1" smd rect (at -2.32 0) (size 1.5 2.75) (layers "B.Cu" "B.Paste" "B.Mask")
      (net 9 "/Power Supply/PoE/VDD_POE_IN") (pintype "passive"))
    (pad "2" smd rect (at 2.32 0) (size 1.5 2.75) (layers "B.Cu" "B.Paste" "B.Mask")
      (net 11 "GNDD") (pintype "passive"))
  )
)
